(kicad_pcb
	(version 20260206)
	(generator "pcbnew")
	(generator_version "10.0")
	(general
		(thickness 1.6)
		(legacy_teardrops no)
	)
	(paper "A4")
	(title_block
		(title "03242023_DA0F0TMBIJ0_F0T_Motherboard_J_brd_V01_OCP.brd")
		(comment 1 "Grand Teton / footprints 5413-5418 of 6105")
	)
	(layers
		(0 "F.Cu" signal "TOP")
		(4 "In1.Cu" signal "GND")
		(6 "In2.Cu" signal "IN1")
		(8 "In3.Cu" signal "GND1")
		(10 "In4.Cu" signal "IN2")
		(12 "In5.Cu" signal "GND2")
		(14 "In6.Cu" signal "IN3")
		(16 "In7.Cu" signal "GND3")
		(18 "In8.Cu" signal "VCC")
		(20 "In9.Cu" signal "VCC1")
		(22 "In10.Cu" signal "GND4")
		(24 "In11.Cu" signal "IN4")
		(26 "In12.Cu" signal "GND5")
		(28 "In13.Cu" signal "IN5")
		(30 "In14.Cu" signal "GND6")
		(32 "In15.Cu" signal "IN6")
		(34 "In16.Cu" signal "GND7")
		(2 "B.Cu" signal "BOTTOM")
		(9 "F.Adhes" user "F.Adhesive")
		(11 "B.Adhes" user "B.Adhesive")
		(13 "F.Paste" user "Package Geometry/Pastemask Top")
		(15 "B.Paste" user "Package Geometry/Pastemask Bottom")
		(5 "F.SilkS" user "Ref Des/Silkscreen Top")
		(7 "B.SilkS" user "Ref Des/Silkscreen Bottom")
		(1 "F.Mask" user "Board Geometry/Soldermask Top")
		(3 "B.Mask" user "Board Geometry/Soldermask Bottom")
		(17 "Dwgs.User" user "User.Drawings")
		(19 "Cmts.User" user "User.Comments")
		(21 "Eco1.User" user "User.Eco1")
		(23 "Eco2.User" user "User.Eco2")
		(25 "Edge.Cuts" user "Board Geometry/Outline")
		(27 "Margin" user)
		(31 "F.CrtYd" user "Package Geometry/Place Bound Top")
		(29 "B.CrtYd" user "Package Geometry/Place Bound Bottom")
		(35 "F.Fab" user "Ref Des/Assembly Top")
		(33 "B.Fab" user "Ref Des/Assembly Bottom")
	)
	(footprint ""
		(layer "B.Cu")
		(at 90.410284 -184.01665 90)
		(property "Reference" "R1007"
			(at 0 0 90)
			(layer "B.SilkS")
			(hide yes)
			(effects
				(font
					(size 1.27 1.27)
				)
				(justify mirror)
			)
		)
		(property "Value" ""
			(at 0 0 90)
			(layer "B.Fab")
			(effects
				(font
					(size 1.27 1.27)
				)
				(justify mirror)
			)
		)
		(duplicate_pad_numbers_are_jumpers no)
		(fp_line
			(start 0.7874 -0.4064)
			(end -0.7874 -0.4064)
			(stroke
				(width 0.1524)
				(type default)
			)
			(layer "B.SilkS")
		)
		(fp_line
			(start -0.7874 -0.4064)
			(end -0.7874 0.4064)
			(stroke
				(width 0.1524)
				(type default)
			)
			(layer "B.SilkS")
		)
		(fp_line
			(start 0.7874 0.4064)
			(end 0.7874 -0.4064)
			(stroke
				(width 0.1524)
				(type default)
			)
			(layer "B.SilkS")
		)
		(fp_line
			(start -0.7874 0.4064)
			(end 0.7874 0.4064)
			(stroke
				(width 0.1524)
				(type default)
			)
			(layer "B.SilkS")
		)
		(fp_line
			(start 0.67945 -0.305054)
			(end 0.12065 -0.305054)
			(stroke
				(width 0.1)
				(type default)
			)
			(layer "B.Fab")
		)
		(fp_line
			(start 0.12065 -0.305054)
			(end 0.12065 -0.2794)
			(stroke
				(width 0.1)
				(type default)
			)
			(layer "B.Fab")
		)
		(fp_line
			(start -0.12065 -0.3048)
			(end -0.67945 -0.3048)
			(stroke
				(width 0.1)
				(type default)
			)
			(layer "B.Fab")
		)
		(fp_line
			(start -0.67945 -0.3048)
			(end -0.67945 0.3048)
			(stroke
				(width 0.1)
				(type default)
			)
			(layer "B.Fab")
		)
		(fp_line
			(start 0.12065 -0.2794)
			(end -0.12065 -0.2794)
			(stroke
				(width 0.1)
				(type default)
			)
			(layer "B.Fab")
		)
		(fp_line
			(start -0.12065 -0.2794)
			(end -0.12065 -0.3048)
			(stroke
				(width 0.1)
				(type default)
			)
			(layer "B.Fab")
		)
		(fp_line
			(start 0.12065 0.2794)
			(end 0.12065 0.3048)
			(stroke
				(width 0.1)
				(type default)
			)
			(layer "B.Fab")
		)
		(fp_line
			(start -0.120396 0.2794)
			(end 0.12065 0.2794)
			(stroke
				(width 0.1)
				(type default)
			)
			(layer "B.Fab")
		)
		(fp_line
			(start 0.67945 0.3048)
			(end 0.67945 -0.305054)
			(stroke
				(width 0.1)
				(type default)
			)
			(layer "B.Fab")
		)
		(fp_line
			(start 0.12065 0.3048)
			(end 0.67945 0.3048)
			(stroke
				(width 0.1)
				(type default)
			)
			(layer "B.Fab")
		)
		(fp_line
			(start -0.120396 0.3048)
			(end -0.120396 0.2794)
			(stroke
				(width 0.1)
				(type default)
			)
			(layer "B.Fab")
		)
		(fp_line
			(start -0.67945 0.3048)
			(end -0.120396 0.3048)
			(stroke
				(width 0.1)
				(type default)
			)
			(layer "B.Fab")
		)
		(pad "1" smd circle
			(at 0.40005 0 270)
			(size 0 0)
			(layers "B.Cu" "B.Mask" "B.Paste")
			(net "PVNN_TERM_CPU1")
		)
		(pad "2" smd circle
			(at -0.40005 0 270)
			(size 0 0)
			(layers "B.Cu" "B.Mask" "B.Paste")
			(net "FM_PEHPCPU1_ALERT_N")
		)
	)
	(footprint ""
		(layer "B.Cu")
		(at 156.1465 -194.55511 -90)
		(property "Reference" "R70"
			(at 0 0 90)
			(layer "B.SilkS")
			(hide yes)
			(effects
				(font
					(size 1.27 1.27)
				)
				(justify mirror)
			)
		)
		(property "Value" ""
			(at 0 0 90)
			(layer "B.Fab")
			(effects
				(font
					(size 1.27 1.27)
				)
				(justify mirror)
			)
		)
		(duplicate_pad_numbers_are_jumpers no)
		(fp_line
			(start -0.7874 0.4064)
			(end 0.7874 0.4064)
			(stroke
				(width 0.1524)
				(type default)
			)
			(layer "B.SilkS")
		)
		(fp_line
			(start 0.7874 0.4064)
			(end 0.7874 -0.4064)
			(stroke
				(width 0.1524)
				(type default)
			)
			(layer "B.SilkS")
		)
		(fp_line
			(start -0.7874 -0.4064)
			(end -0.7874 0.4064)
			(stroke
				(width 0.1524)
				(type default)
			)
			(layer "B.SilkS")
		)
		(fp_line
			(start 0.7874 -0.4064)
			(end -0.7874 -0.4064)
			(stroke
				(width 0.1524)
				(type default)
			)
			(layer "B.SilkS")
		)
		(fp_line
			(start -0.67945 0.3048)
			(end -0.120396 0.3048)
			(stroke
				(width 0.1)
				(type default)
			)
			(layer "B.Fab")
		)
		(fp_line
			(start -0.120396 0.3048)
			(end -0.120396 0.2794)
			(stroke
				(width 0.1)
				(type default)
			)
			(layer "B.Fab")
		)
		(fp_line
			(start 0.12065 0.3048)
			(end 0.67945 0.3048)
			(stroke
				(width 0.1)
				(type default)
			)
			(layer "B.Fab")
		)
		(fp_line
			(start 0.67945 0.3048)
			(end 0.67945 -0.305054)
			(stroke
				(width 0.1)
				(type default)
			)
			(layer "B.Fab")
		)
		(fp_line
			(start -0.120396 0.2794)
			(end 0.12065 0.2794)
			(stroke
				(width 0.1)
				(type default)
			)
			(layer "B.Fab")
		)
		(fp_line
			(start 0.12065 0.2794)
			(end 0.12065 0.3048)
			(stroke
				(width 0.1)
				(type default)
			)
			(layer "B.Fab")
		)
		(fp_line
			(start -0.12065 -0.2794)
			(end -0.12065 -0.3048)
			(stroke
				(width 0.1)
				(type default)
			)
			(layer "B.Fab")
		)
		(fp_line
			(start 0.12065 -0.2794)
			(end -0.12065 -0.2794)
			(stroke
				(width 0.1)
				(type default)
			)
			(layer "B.Fab")
		)
		(fp_line
			(start -0.67945 -0.3048)
			(end -0.67945 0.3048)
			(stroke
				(width 0.1)
				(type default)
			)
			(layer "B.Fab")
		)
		(fp_line
			(start -0.12065 -0.3048)
			(end -0.67945 -0.3048)
			(stroke
				(width 0.1)
				(type default)
			)
			(layer "B.Fab")
		)
		(fp_line
			(start 0.12065 -0.305054)
			(end 0.12065 -0.2794)
			(stroke
				(width 0.1)
				(type default)
			)
			(layer "B.Fab")
		)
		(fp_line
			(start 0.67945 -0.305054)
			(end 0.12065 -0.305054)
			(stroke
				(width 0.1)
				(type default)
			)
			(layer "B.Fab")
		)
		(pad "1" smd circle
			(at 0.40005 0 90)
			(size 0 0)
			(layers "B.Cu" "B.Mask" "B.Paste")
			(net "PWRGD_PLT_AUX_CPU1_LVT3")
		)
		(pad "2" smd circle
			(at -0.40005 0 90)
			(size 0 0)
			(layers "B.Cu" "B.Mask" "B.Paste")
			(net "GND")
		)
	)
	(footprint ""
		(layer "B.Cu")
		(at 296.183558 -194.26555 90)
		(property "Reference" "R175"
			(at 0 0 90)
			(layer "B.SilkS")
			(hide yes)
			(effects
				(font
					(size 1.27 1.27)
				)
				(justify mirror)
			)
		)
		(property "Value" ""
			(at 0 0 90)
			(layer "B.Fab")
			(effects
				(font
					(size 1.27 1.27)
				)
				(justify mirror)
			)
		)
		(duplicate_pad_numbers_are_jumpers no)
		(fp_line
			(start 0.7874 -0.4064)
			(end -0.7874 -0.4064)
			(stroke
				(width 0.1524)
				(type default)
			)
			(layer "B.SilkS")
		)
		(fp_line
			(start -0.7874 -0.4064)
			(end -0.7874 0.4064)
			(stroke
				(width 0.1524)
				(type default)
			)
			(layer "B.SilkS")
		)
		(fp_line
			(start 0.7874 0.4064)
			(end 0.7874 -0.4064)
			(stroke
				(width 0.1524)
				(type default)
			)
			(layer "B.SilkS")
		)
		(fp_line
			(start -0.7874 0.4064)
			(end 0.7874 0.4064)
			(stroke
				(width 0.1524)
				(type default)
			)
			(layer "B.SilkS")
		)
		(fp_line
			(start 0.67945 -0.305054)
			(end 0.12065 -0.305054)
			(stroke
				(width 0.1)
				(type default)
			)
			(layer "B.Fab")
		)
		(fp_line
			(start 0.12065 -0.305054)
			(end 0.12065 -0.2794)
			(stroke
				(width 0.1)
				(type default)
			)
			(layer "B.Fab")
		)
		(fp_line
			(start -0.12065 -0.3048)
			(end -0.67945 -0.3048)
			(stroke
				(width 0.1)
				(type default)
			)
			(layer "B.Fab")
		)
		(fp_line
			(start -0.67945 -0.3048)
			(end -0.67945 0.3048)
			(stroke
				(width 0.1)
				(type default)
			)
			(layer "B.Fab")
		)
		(fp_line
			(start 0.12065 -0.2794)
			(end -0.12065 -0.2794)
			(stroke
				(width 0.1)
				(type default)
			)
			(layer "B.Fab")
		)
		(fp_line
			(start -0.12065 -0.2794)
			(end -0.12065 -0.3048)
			(stroke
				(width 0.1)
				(type default)
			)
			(layer "B.Fab")
		)
		(fp_line
			(start 0.12065 0.2794)
			(end 0.12065 0.3048)
			(stroke
				(width 0.1)
				(type default)
			)
			(layer "B.Fab")
		)
		(fp_line
			(start -0.120396 0.2794)
			(end 0.12065 0.2794)
			(stroke
				(width 0.1)
				(type default)
			)
			(layer "B.Fab")
		)
		(fp_line
			(start 0.67945 0.3048)
			(end 0.67945 -0.305054)
			(stroke
				(width 0.1)
				(type default)
			)
			(layer "B.Fab")
		)
		(fp_line
			(start 0.12065 0.3048)
			(end 0.67945 0.3048)
			(stroke
				(width 0.1)
				(type default)
			)
			(layer "B.Fab")
		)
		(fp_line
			(start -0.120396 0.3048)
			(end -0.120396 0.2794)
			(stroke
				(width 0.1)
				(type default)
			)
			(layer "B.Fab")
		)
		(fp_line
			(start -0.67945 0.3048)
			(end -0.120396 0.3048)
			(stroke
				(width 0.1)
				(type default)
			)
			(layer "B.Fab")
		)
		(pad "1" smd circle
			(at 0.40005 0 270)
			(size 0 0)
			(layers "B.Cu" "B.Mask" "B.Paste")
			(net "PWRGD_DRAMPWRGD_CPU0_AB_LVC1_R2")
		)
		(pad "2" smd circle
			(at -0.40005 0 270)
			(size 0 0)
			(layers "B.Cu" "B.Mask" "B.Paste")
			(net "PVCCD_HV_CPU0")
		)
	)
	(footprint ""
		(layer "B.Cu")
		(at 343.050368 -30.636972)
		(property "Reference" "R1309"
			(at 0 0 0)
			(layer "B.SilkS")
			(hide yes)
			(effects
				(font
					(size 1.27 1.27)
				)
				(justify mirror)
			)
		)
		(property "Value" ""
			(at 0 0 0)
			(layer "B.Fab")
			(effects
				(font
					(size 1.27 1.27)
				)
				(justify mirror)
			)
		)
		(duplicate_pad_numbers_are_jumpers no)
		(fp_line
			(start -0.7874 -0.4064)
			(end -0.7874 0.4064)
			(stroke
				(width 0.1524)
				(type default)
			)
			(layer "B.SilkS")
		)
		(fp_line
			(start -0.7874 0.4064)
			(end 0.7874 0.4064)
			(stroke
				(width 0.1524)
				(type default)
			)
			(layer "B.SilkS")
		)
		(fp_line
			(start 0.7874 -0.4064)
			(end -0.7874 -0.4064)
			(stroke
				(width 0.1524)
				(type default)
			)
			(layer "B.SilkS")
		)
		(fp_line
			(start 0.7874 0.4064)
			(end 0.7874 -0.4064)
			(stroke
				(width 0.1524)
				(type default)
			)
			(layer "B.SilkS")
		)
		(fp_line
			(start -0.67945 -0.3048)
			(end -0.67945 0.3048)
			(stroke
				(width 0.1)
				(type default)
			)
			(layer "B.Fab")
		)
		(fp_line
			(start -0.67945 0.3048)
			(end -0.120396 0.3048)
			(stroke
				(width 0.1)
				(type default)
			)
			(layer "B.Fab")
		)
		(fp_line
			(start -0.12065 -0.3048)
			(end -0.67945 -0.3048)
			(stroke
				(width 0.1)
				(type default)
			)
			(layer "B.Fab")
		)
		(fp_line
			(start -0.12065 -0.2794)
			(end -0.12065 -0.3048)
			(stroke
				(width 0.1)
				(type default)
			)
			(layer "B.Fab")
		)
		(fp_line
			(start -0.120396 0.2794)
			(end 0.12065 0.2794)
			(stroke
				(width 0.1)
				(type default)
			)
			(layer "B.Fab")
		)
		(fp_line
			(start -0.120396 0.3048)
			(end -0.120396 0.2794)
			(stroke
				(width 0.1)
				(type default)
			)
			(layer "B.Fab")
		)
		(fp_line
			(start 0.12065 -0.305054)
			(end 0.12065 -0.2794)
			(stroke
				(width 0.1)
				(type default)
			)
			(layer "B.Fab")
		)
		(fp_line
			(start 0.12065 -0.2794)
			(end -0.12065 -0.2794)
			(stroke
				(width 0.1)
				(type default)
			)
			(layer "B.Fab")
		)
		(fp_line
			(start 0.12065 0.2794)
			(end 0.12065 0.3048)
			(stroke
				(width 0.1)
				(type default)
			)
			(layer "B.Fab")
		)
		(fp_line
			(start 0.12065 0.3048)
			(end 0.67945 0.3048)
			(stroke
				(width 0.1)
				(type default)
			)
			(layer "B.Fab")
		)
		(fp_line
			(start 0.67945 -0.305054)
			(end 0.12065 -0.305054)
			(stroke
				(width 0.1)
				(type default)
			)
			(layer "B.Fab")
		)
		(fp_line
			(start 0.67945 0.3048)
			(end 0.67945 -0.305054)
			(stroke
				(width 0.1)
				(type default)
			)
			(layer "B.Fab")
		)
		(pad "1" smd circle
			(at 0.40005 0 180)
			(size 0 0)
			(layers "B.Cu" "B.Mask" "B.Paste")
			(net "IRQ_SMI_ACTIVE_N")
		)
		(pad "2" smd circle
			(at -0.40005 0 180)
			(size 0 0)
			(layers "B.Cu" "B.Mask" "B.Paste")
			(net "IRQ_SMI_ACTIVE_BMC_N")
		)
	)
	(footprint ""
		(layer "B.Cu")
		(at 423.683938 -135.769096 180)
		(property "Reference" "PR4220"
			(at 0 0 0)
			(layer "B.SilkS")
			(hide yes)
			(effects
				(font
					(size 1.27 1.27)
				)
				(justify mirror)
			)
		)
		(property "Value" ""
			(at 0 0 0)
			(layer "B.Fab")
			(effects
				(font
					(size 1.27 1.27)
				)
				(justify mirror)
			)
		)
		(duplicate_pad_numbers_are_jumpers no)
		(fp_line
			(start 0.7874 0.4064)
			(end 0.7874 -0.4064)
			(stroke
				(width 0.1524)
				(type default)
			)
			(layer "B.SilkS")
		)
		(fp_line
			(start 0.7874 -0.4064)
			(end -0.7874 -0.4064)
			(stroke
				(width 0.1524)
				(type default)
			)
			(layer "B.SilkS")
		)
		(fp_line
			(start -0.7874 0.4064)
			(end 0.7874 0.4064)
			(stroke
				(width 0.1524)
				(type default)
			)
			(layer "B.SilkS")
		)
		(fp_line
			(start -0.7874 -0.4064)
			(end -0.7874 0.4064)
			(stroke
				(width 0.1524)
				(type default)
			)
			(layer "B.SilkS")
		)
		(fp_line
			(start 0.67945 0.3048)
			(end 0.67945 -0.305054)
			(stroke
				(width 0.1)
				(type default)
			)
			(layer "B.Fab")
		)
		(fp_line
			(start 0.67945 -0.305054)
			(end 0.12065 -0.305054)
			(stroke
				(width 0.1)
				(type default)
			)
			(layer "B.Fab")
		)
		(fp_line
			(start 0.12065 0.3048)
			(end 0.67945 0.3048)
			(stroke
				(width 0.1)
				(type default)
			)
			(layer "B.Fab")
		)
		(fp_line
			(start 0.12065 0.2794)
			(end 0.12065 0.3048)
			(stroke
				(width 0.1)
				(type default)
			)
			(layer "B.Fab")
		)
		(fp_line
			(start 0.12065 -0.2794)
			(end -0.12065 -0.2794)
			(stroke
				(width 0.1)
				(type default)
			)
			(layer "B.Fab")
		)
		(fp_line
			(start 0.12065 -0.305054)
			(end 0.12065 -0.2794)
			(stroke
				(width 0.1)
				(type default)
			)
			(layer "B.Fab")
		)
		(fp_line
			(start -0.120396 0.3048)
			(end -0.120396 0.2794)
			(stroke
				(width 0.1)
				(type default)
			)
			(layer "B.Fab")
		)
		(fp_line
			(start -0.120396 0.2794)
			(end 0.12065 0.2794)
			(stroke
				(width 0.1)
				(type default)
			)
			(layer "B.Fab")
		)
		(fp_line
			(start -0.12065 -0.2794)
			(end -0.12065 -0.3048)
			(stroke
				(width 0.1)
				(type default)
			)
			(layer "B.Fab")
		)
		(fp_line
			(start -0.12065 -0.3048)
			(end -0.67945 -0.3048)
			(stroke
				(width 0.1)
				(type default)
			)
			(layer "B.Fab")
		)
		(fp_line
			(start -0.67945 0.3048)
			(end -0.120396 0.3048)
			(stroke
				(width 0.1)
				(type default)
			)
			(layer "B.Fab")
		)
		(fp_line
			(start -0.67945 -0.3048)
			(end -0.67945 0.3048)
			(stroke
				(width 0.1)
				(type default)
			)
			(layer "B.Fab")
		)
		(pad "1" smd circle
			(at 0.40005 0)
			(size 0 0)
			(layers "B.Cu" "B.Mask" "B.Paste")
			(net "PVCCINFAON_CPU0_CSPIN")
		)
		(pad "2" smd circle
			(at -0.40005 0)
			(size 0 0)
			(layers "B.Cu" "B.Mask" "B.Paste")
			(net "GND")
		)
	)
	(footprint ""
		(layer "B.Cu")
		(at 182.871618 -18.710148 90)
		(property "Reference" "R3239"
			(at 0 0 90)
			(layer "B.SilkS")
			(hide yes)
			(effects
				(font
					(size 1.27 1.27)
				)
				(justify mirror)
			)
		)
		(property "Value" ""
			(at 0 0 90)
			(layer "B.Fab")
			(effects
				(font
					(size 1.27 1.27)
				)
				(justify mirror)
			)
		)
		(duplicate_pad_numbers_are_jumpers no)
		(fp_line
			(start 0.7874 -0.4064)
			(end -0.7874 -0.4064)
			(stroke
				(width 0.1524)
				(type default)
			)
			(layer "B.SilkS")
		)
		(fp_line
			(start -0.7874 -0.4064)
			(end -0.7874 0.4064)
			(stroke
				(width 0.1524)
				(type default)
			)
			(layer "B.SilkS")
		)
		(fp_line
			(start 0.7874 0.4064)
			(end 0.7874 -0.4064)
			(stroke
				(width 0.1524)
				(type default)
			)
			(layer "B.SilkS")
		)
		(fp_line
			(start -0.7874 0.4064)
			(end 0.7874 0.4064)
			(stroke
				(width 0.1524)
				(type default)
			)
			(layer "B.SilkS")
		)
		(fp_line
			(start 0.67945 -0.305054)
			(end 0.12065 -0.305054)
			(stroke
				(width 0.1)
				(type default)
			)
			(layer "B.Fab")
		)
		(fp_line
			(start 0.12065 -0.305054)
			(end 0.12065 -0.2794)
			(stroke
				(width 0.1)
				(type default)
			)
			(layer "B.Fab")
		)
		(fp_line
			(start -0.12065 -0.3048)
			(end -0.67945 -0.3048)
			(stroke
				(width 0.1)
				(type default)
			)
			(layer "B.Fab")
		)
		(fp_line
			(start -0.67945 -0.3048)
			(end -0.67945 0.3048)
			(stroke
				(width 0.1)
				(type default)
			)
			(layer "B.Fab")
		)
		(fp_line
			(start 0.12065 -0.2794)
			(end -0.12065 -0.2794)
			(stroke
				(width 0.1)
				(type default)
			)
			(layer "B.Fab")
		)
		(fp_line
			(start -0.12065 -0.2794)
			(end -0.12065 -0.3048)
			(stroke
				(width 0.1)
				(type default)
			)
			(layer "B.Fab")
		)
		(fp_line
			(start 0.12065 0.2794)
			(end 0.12065 0.3048)
			(stroke
				(width 0.1)
				(type default)
			)
			(layer "B.Fab")
		)
		(fp_line
			(start -0.120396 0.2794)
			(end 0.12065 0.2794)
			(stroke
				(width 0.1)
				(type default)
			)
			(layer "B.Fab")
		)
		(fp_line
			(start 0.67945 0.3048)
			(end 0.67945 -0.305054)
			(stroke
				(width 0.1)
				(type default)
			)
			(layer "B.Fab")
		)
		(fp_line
			(start 0.12065 0.3048)
			(end 0.67945 0.3048)
			(stroke
				(width 0.1)
				(type default)
			)
			(layer "B.Fab")
		)
		(fp_line
			(start -0.120396 0.3048)
			(end -0.120396 0.2794)
			(stroke
				(width 0.1)
				(type default)
			)
			(layer "B.Fab")
		)
		(fp_line
			(start -0.67945 0.3048)
			(end -0.120396 0.3048)
			(stroke
				(width 0.1)
				(type default)
			)
			(layer "B.Fab")
		)
		(pad "1" smd circle
			(at 0.40005 0 270)
			(size 0 0)
			(layers "B.Cu" "B.Mask" "B.Paste")
			(net "SMB_OCP_SFF_3V3AUX_SDA")
		)
		(pad "2" smd circle
			(at -0.40005 0 270)
			(size 0 0)
			(layers "B.Cu" "B.Mask" "B.Paste")
			(net "SMB_OCP_SFF_3V3AUX_SDA_R0")
		)
	)
)
